# S9S_MB_2U (Grand Teton) — schematic netlist excerpt (pin names and nets, part order shuffled) for the footprints in the layout excerpt that follows; sources: Cadence DE-HDL packaged netlist, KiCad conversion of 03242023_DA0F0TMBIJ0_F0T_Motherboard_J_brd_V01_OCP.brd

R4480  Q_RES  33.2 1% CHIP  pkg 0402LF  page 237 : A = SMB_HOST_CLK_BUF_ISO_3V3AUX_SCL ; B = SMB_HOST_9ZXL045_3V3AUX_SCL
PR442  Q_RES  0 5% CHIP  pkg 0402LF  page 276 : A = P5V ; B = PVCCFA_EHV_CPU0_PVCC

(kicad_pcb
	(version 20260206)
	(generator "pcbnew")
	(generator_version "10.0")
	(general
		(thickness 1.6)
		(legacy_teardrops no)
	)
	(paper "A4")
	(title_block
		(title "03242023_DA0F0TMBIJ0_F0T_Motherboard_J_brd_V01_OCP.brd")
		(comment 1 "Grand Teton / footprints 4054-4055 of 6105")
	)
	(layers
		(0 "F.Cu" signal "TOP")
		(4 "In1.Cu" signal "GND")
		(6 "In2.Cu" signal "IN1")
		(8 "In3.Cu" signal "GND1")
		(10 "In4.Cu" signal "IN2")
		(12 "In5.Cu" signal "GND2")
		(14 "In6.Cu" signal "IN3")
		(16 "In7.Cu" signal "GND3")
		(18 "In8.Cu" signal "VCC")
		(20 "In9.Cu" signal "VCC1")
		(22 "In10.Cu" signal "GND4")
		(24 "In11.Cu" signal "IN4")
		(26 "In12.Cu" signal "GND5")
		(28 "In13.Cu" signal "IN5")
		(30 "In14.Cu" signal "GND6")
		(32 "In15.Cu" signal "IN6")
		(34 "In16.Cu" signal "GND7")
		(2 "B.Cu" signal "BOTTOM")
		(9 "F.Adhes" user "F.Adhesive")
		(11 "B.Adhes" user "B.Adhesive")
		(13 "F.Paste" user "Package Geometry/Pastemask Top")
		(15 "B.Paste" user "Package Geometry/Pastemask Bottom")
		(5 "F.SilkS" user "Ref Des/Silkscreen Top")
		(7 "B.SilkS" user "Ref Des/Silkscreen Bottom")
		(1 "F.Mask" user "Board Geometry/Soldermask Top")
		(3 "B.Mask" user "Board Geometry/Soldermask Bottom")
		(17 "Dwgs.User" user "User.Drawings")
		(19 "Cmts.User" user "User.Comments")
		(21 "Eco1.User" user "User.Eco1")
		(23 "Eco2.User" user "User.Eco2")
		(25 "Edge.Cuts" user "Board Geometry/Outline")
		(27 "Margin" user)
		(31 "F.CrtYd" user "Package Geometry/Place Bound Top")
		(29 "B.CrtYd" user "Package Geometry/Place Bound Bottom")
		(35 "F.Fab" user "Ref Des/Assembly Top")
		(33 "B.Fab" user "Ref Des/Assembly Bottom")
	)
	(footprint ""
		(layer "F.Cu")
		(at 262.450072 -127.965708 -90)
		(property "Reference" "R4480"
			(at 0 0 270)
			(layer "F.SilkS")
			(hide yes)
			(effects
				(font
					(size 1.27 1.27)
				)
			)
		)
		(property "Value" ""
			(at 0 0 270)
			(layer "F.Fab")
			(effects
				(font
					(size 1.27 1.27)
				)
			)
		)
		(duplicate_pad_numbers_are_jumpers no)
		(fp_line
			(start -0.7874 0.4064)
			(end -0.7874 -0.4064)
			(stroke
				(width 0.1524)
				(type default)
			)
			(layer "F.SilkS")
		)
		(fp_line
			(start 0.7874 0.4064)
			(end -0.7874 0.4064)
			(stroke
				(width 0.1524)
				(type default)
			)
			(layer "F.SilkS")
		)
		(fp_line
			(start -0.7874 -0.4064)
			(end 0.7874 -0.4064)
			(stroke
				(width 0.1524)
				(type default)
			)
			(layer "F.SilkS")
		)
		(fp_line
			(start 0.7874 -0.4064)
			(end 0.7874 0.4064)
			(stroke
				(width 0.1524)
				(type default)
			)
			(layer "F.SilkS")
		)
		(fp_line
			(start -0.67945 0.3048)
			(end -0.67945 -0.305054)
			(stroke
				(width 0.1)
				(type default)
			)
			(layer "F.Fab")
		)
		(fp_line
			(start -0.12065 0.3048)
			(end -0.67945 0.3048)
			(stroke
				(width 0.1)
				(type default)
			)
			(layer "F.Fab")
		)
		(fp_line
			(start 0.120396 0.3048)
			(end 0.120396 0.2794)
			(stroke
				(width 0.1)
				(type default)
			)
			(layer "F.Fab")
		)
		(fp_line
			(start 0.67945 0.3048)
			(end 0.120396 0.3048)
			(stroke
				(width 0.1)
				(type default)
			)
			(layer "F.Fab")
		)
		(fp_line
			(start -0.12065 0.2794)
			(end -0.12065 0.3048)
			(stroke
				(width 0.1)
				(type default)
			)
			(layer "F.Fab")
		)
		(fp_line
			(start 0.120396 0.2794)
			(end -0.12065 0.2794)
			(stroke
				(width 0.1)
				(type default)
			)
			(layer "F.Fab")
		)
		(fp_line
			(start -0.12065 -0.2794)
			(end 0.12065 -0.2794)
			(stroke
				(width 0.1)
				(type default)
			)
			(layer "F.Fab")
		)
		(fp_line
			(start 0.12065 -0.2794)
			(end 0.12065 -0.3048)
			(stroke
				(width 0.1)
				(type default)
			)
			(layer "F.Fab")
		)
		(fp_line
			(start 0.12065 -0.3048)
			(end 0.67945 -0.3048)
			(stroke
				(width 0.1)
				(type default)
			)
			(layer "F.Fab")
		)
		(fp_line
			(start 0.67945 -0.3048)
			(end 0.67945 0.3048)
			(stroke
				(width 0.1)
				(type default)
			)
			(layer "F.Fab")
		)
		(fp_line
			(start -0.67945 -0.305054)
			(end -0.12065 -0.305054)
			(stroke
				(width 0.1)
				(type default)
			)
			(layer "F.Fab")
		)
		(fp_line
			(start -0.12065 -0.305054)
			(end -0.12065 -0.2794)
			(stroke
				(width 0.1)
				(type default)
			)
			(layer "F.Fab")
		)
		(pad "1" smd circle
			(at -0.40005 0 270)
			(size 0 0)
			(layers "F.Cu" "F.Mask" "F.Paste")
			(net "SMB_HOST_CLK_BUF_ISO_3V3AUX_SCL")
		)
		(pad "2" smd circle
			(at 0.40005 0 270)
			(size 0 0)
			(layers "F.Cu" "F.Mask" "F.Paste")
			(net "SMB_HOST_9ZXL045_3V3AUX_SCL")
		)
	)
	(footprint ""
		(layer "F.Cu")
		(at 421.92448 -156.327348 -90)
		(property "Reference" "PR442"
			(at 0 0 270)
			(layer "F.SilkS")
			(hide yes)
			(effects
				(font
					(size 1.27 1.27)
				)
			)
		)
		(property "Value" ""
			(at 0 0 270)
			(layer "F.Fab")
			(effects
				(font
					(size 1.27 1.27)
				)
			)
		)
		(duplicate_pad_numbers_are_jumpers no)
		(fp_line
			(start -0.7874 0.4064)
			(end -0.7874 -0.4064)
			(stroke
				(width 0.1524)
				(type default)
			)
			(layer "F.SilkS")
		)
		(fp_line
			(start 0.7874 0.4064)
			(end -0.7874 0.4064)
			(stroke
				(width 0.1524)
				(type default)
			)
			(layer "F.SilkS")
		)
		(fp_line
			(start -0.7874 -0.4064)
			(end 0.7874 -0.4064)
			(stroke
				(width 0.1524)
				(type default)
			)
			(layer "F.SilkS")
		)
		(fp_line
			(start 0.7874 -0.4064)
			(end 0.7874 0.4064)
			(stroke
				(width 0.1524)
				(type default)
			)
			(layer "F.SilkS")
		)
		(fp_line
			(start -0.67945 0.3048)
			(end -0.67945 -0.305054)
			(stroke
				(width 0.1)
				(type default)
			)
			(layer "F.Fab")
		)
		(fp_line
			(start -0.12065 0.3048)
			(end -0.67945 0.3048)
			(stroke
				(width 0.1)
				(type default)
			)
			(layer "F.Fab")
		)
		(fp_line
			(start 0.120396 0.3048)
			(end 0.120396 0.2794)
			(stroke
				(width 0.1)
				(type default)
			)
			(layer "F.Fab")
		)
		(fp_line
			(start 0.67945 0.3048)
			(end 0.120396 0.3048)
			(stroke
				(width 0.1)
				(type default)
			)
			(layer "F.Fab")
		)
		(fp_line
			(start -0.12065 0.2794)
			(end -0.12065 0.3048)
			(stroke
				(width 0.1)
				(type default)
			)
			(layer "F.Fab")
		)
		(fp_line
			(start 0.120396 0.2794)
			(end -0.12065 0.2794)
			(stroke
				(width 0.1)
				(type default)
			)
			(layer "F.Fab")
		)
		(fp_line
			(start -0.12065 -0.2794)
			(end 0.12065 -0.2794)
			(stroke
				(width 0.1)
				(type default)
			)
			(layer "F.Fab")
		)
		(fp_line
			(start 0.12065 -0.2794)
			(end 0.12065 -0.3048)
			(stroke
				(width 0.1)
				(type default)
			)
			(layer "F.Fab")
		)
		(fp_line
			(start 0.12065 -0.3048)
			(end 0.67945 -0.3048)
			(stroke
				(width 0.1)
				(type default)
			)
			(layer "F.Fab")
		)
		(fp_line
			(start 0.67945 -0.3048)
			(end 0.67945 0.3048)
			(stroke
				(width 0.1)
				(type default)
			)
			(layer "F.Fab")
		)
		(fp_line
			(start -0.67945 -0.305054)
			(end -0.12065 -0.305054)
			(stroke
				(width 0.1)
				(type default)
			)
			(layer "F.Fab")
		)
		(fp_line
			(start -0.12065 -0.305054)
			(end -0.12065 -0.2794)
			(stroke
				(width 0.1)
				(type default)
			)
			(layer "F.Fab")
		)
		(pad "1" smd circle
			(at -0.40005 0 270)
			(size 0 0)
			(layers "F.Cu" "F.Mask" "F.Paste")
			(net "P5V")
		)
		(pad "2" smd circle
			(at 0.40005 0 270)
			(size 0 0)
			(layers "F.Cu" "F.Mask" "F.Paste")
			(net "PVCCFA_EHV_CPU0_PVCC")
		)
	)
)
